(kicad_pcb
	(version 20260206)
	(generator "pcbnew")
	(generator_version "10.0")
	(general
		(thickness 1.6)
		(legacy_teardrops no)
	)
	(paper "A4")
	(title_block
		(title "12092022_DA0F0TYB4D0_F0T_Panel_BD_Front_D_brd_v02_OCP.brd")
		(comment 1 "Grand Teton / footprints 109-115 of 128")
	)
	(layers
		(0 "F.Cu" signal "TOP")
		(4 "In1.Cu" signal "GND")
		(6 "In2.Cu" signal "GND1")
		(2 "B.Cu" signal "BOTTOM")
		(9 "F.Adhes" user "F.Adhesive")
		(11 "B.Adhes" user "B.Adhesive")
		(13 "F.Paste" user "Package Geometry/Pastemask Top")
		(15 "B.Paste" user "Package Geometry/Pastemask Bottom")
		(5 "F.SilkS" user "Ref Des/Silkscreen Top")
		(7 "B.SilkS" user "Ref Des/Silkscreen Bottom")
		(1 "F.Mask" user "Board Geometry/Soldermask Top")
		(3 "B.Mask" user "Board Geometry/Soldermask Bottom")
		(17 "Dwgs.User" user "User.Drawings")
		(19 "Cmts.User" user "User.Comments")
		(21 "Eco1.User" user "User.Eco1")
		(23 "Eco2.User" user "User.Eco2")
		(25 "Edge.Cuts" user "Board Geometry/Outline")
		(27 "Margin" user)
		(31 "F.CrtYd" user "Package Geometry/Place Bound Top")
		(29 "B.CrtYd" user "Package Geometry/Place Bound Bottom")
		(35 "F.Fab" user "Ref Des/Assembly Top")
		(33 "B.Fab" user "Ref Des/Assembly Bottom")
	)
	(footprint ""
		(layer "F.Cu")
		(at 16.51 -19.685 -90)
		(property "Reference" "R29"
			(at -2.032 0.60833 90)
			(unlocked yes)
			(layer "F.SilkS")
			(effects
				(font
					(size 0.7874 0.5842)
					(thickness 0.1524)
				)
			)
		)
		(property "Value" ""
			(at 0 0 270)
			(layer "F.Fab")
			(effects
				(font
					(size 1.27 1.27)
				)
			)
		)
		(duplicate_pad_numbers_are_jumpers no)
		(fp_line
			(start -0.7874 0.4064)
			(end -0.7874 -0.4064)
			(stroke
				(width 0.1524)
				(type default)
			)
			(layer "F.SilkS")
		)
		(fp_line
			(start 0.7874 0.4064)
			(end -0.7874 0.4064)
			(stroke
				(width 0.1524)
				(type default)
			)
			(layer "F.SilkS")
		)
		(fp_line
			(start -0.7874 -0.4064)
			(end 0.7874 -0.4064)
			(stroke
				(width 0.1524)
				(type default)
			)
			(layer "F.SilkS")
		)
		(fp_line
			(start 0.7874 -0.4064)
			(end 0.7874 0.4064)
			(stroke
				(width 0.1524)
				(type default)
			)
			(layer "F.SilkS")
		)
		(fp_line
			(start -0.67945 0.3048)
			(end -0.67945 -0.305054)
			(stroke
				(width 0.1)
				(type default)
			)
			(layer "F.Fab")
		)
		(fp_line
			(start -0.12065 0.3048)
			(end -0.67945 0.3048)
			(stroke
				(width 0.1)
				(type default)
			)
			(layer "F.Fab")
		)
		(fp_line
			(start 0.120396 0.3048)
			(end 0.120396 0.2794)
			(stroke
				(width 0.1)
				(type default)
			)
			(layer "F.Fab")
		)
		(fp_line
			(start 0.67945 0.3048)
			(end 0.120396 0.3048)
			(stroke
				(width 0.1)
				(type default)
			)
			(layer "F.Fab")
		)
		(fp_line
			(start -0.12065 0.2794)
			(end -0.12065 0.3048)
			(stroke
				(width 0.1)
				(type default)
			)
			(layer "F.Fab")
		)
		(fp_line
			(start 0.120396 0.2794)
			(end -0.12065 0.2794)
			(stroke
				(width 0.1)
				(type default)
			)
			(layer "F.Fab")
		)
		(fp_line
			(start -0.12065 -0.2794)
			(end 0.12065 -0.2794)
			(stroke
				(width 0.1)
				(type default)
			)
			(layer "F.Fab")
		)
		(fp_line
			(start 0.12065 -0.2794)
			(end 0.12065 -0.3048)
			(stroke
				(width 0.1)
				(type default)
			)
			(layer "F.Fab")
		)
		(fp_line
			(start 0.12065 -0.3048)
			(end 0.67945 -0.3048)
			(stroke
				(width 0.1)
				(type default)
			)
			(layer "F.Fab")
		)
		(fp_line
			(start 0.67945 -0.3048)
			(end 0.67945 0.3048)
			(stroke
				(width 0.1)
				(type default)
			)
			(layer "F.Fab")
		)
		(fp_line
			(start -0.67945 -0.305054)
			(end -0.12065 -0.305054)
			(stroke
				(width 0.1)
				(type default)
			)
			(layer "F.Fab")
		)
		(fp_line
			(start -0.12065 -0.305054)
			(end -0.12065 -0.2794)
			(stroke
				(width 0.1)
				(type default)
			)
			(layer "F.Fab")
		)
		(pad "1" smd circle
			(at -0.40005 0 270)
			(size 0 0)
			(layers "F.Cu" "F.Mask" "F.Paste")
			(net "P3V3_STBY")
		)
		(pad "2" smd circle
			(at 0.40005 0 270)
			(size 0 0)
			(layers "F.Cu" "F.Mask" "F.Paste")
			(net "THERMAL_OS")
		)
	)
	(footprint ""
		(layer "F.Cu")
		(at 5.969 -56.261 180)
		(property "Reference" "R27"
			(at 2.794 -0.40767 0)
			(unlocked yes)
			(layer "F.SilkS")
			(effects
				(font
					(size 0.7874 0.5842)
					(thickness 0.1524)
				)
			)
		)
		(property "Value" ""
			(at 0 0 180)
			(layer "F.Fab")
			(effects
				(font
					(size 1.27 1.27)
				)
			)
		)
		(duplicate_pad_numbers_are_jumpers no)
		(fp_line
			(start 0.7874 0.4064)
			(end -0.7874 0.4064)
			(stroke
				(width 0.1524)
				(type default)
			)
			(layer "F.SilkS")
		)
		(fp_line
			(start 0.7874 -0.4064)
			(end 0.7874 0.4064)
			(stroke
				(width 0.1524)
				(type default)
			)
			(layer "F.SilkS")
		)
		(fp_line
			(start -0.7874 0.4064)
			(end -0.7874 -0.4064)
			(stroke
				(width 0.1524)
				(type default)
			)
			(layer "F.SilkS")
		)
		(fp_line
			(start -0.7874 -0.4064)
			(end 0.7874 -0.4064)
			(stroke
				(width 0.1524)
				(type default)
			)
			(layer "F.SilkS")
		)
		(fp_line
			(start 0.67945 0.3048)
			(end 0.120396 0.3048)
			(stroke
				(width 0.1)
				(type default)
			)
			(layer "F.Fab")
		)
		(fp_line
			(start 0.67945 -0.3048)
			(end 0.67945 0.3048)
			(stroke
				(width 0.1)
				(type default)
			)
			(layer "F.Fab")
		)
		(fp_line
			(start 0.12065 -0.2794)
			(end 0.12065 -0.3048)
			(stroke
				(width 0.1)
				(type default)
			)
			(layer "F.Fab")
		)
		(fp_line
			(start 0.12065 -0.3048)
			(end 0.67945 -0.3048)
			(stroke
				(width 0.1)
				(type default)
			)
			(layer "F.Fab")
		)
		(fp_line
			(start 0.120396 0.3048)
			(end 0.120396 0.2794)
			(stroke
				(width 0.1)
				(type default)
			)
			(layer "F.Fab")
		)
		(fp_line
			(start 0.120396 0.2794)
			(end -0.12065 0.2794)
			(stroke
				(width 0.1)
				(type default)
			)
			(layer "F.Fab")
		)
		(fp_line
			(start -0.12065 0.3048)
			(end -0.67945 0.3048)
			(stroke
				(width 0.1)
				(type default)
			)
			(layer "F.Fab")
		)
		(fp_line
			(start -0.12065 0.2794)
			(end -0.12065 0.3048)
			(stroke
				(width 0.1)
				(type default)
			)
			(layer "F.Fab")
		)
		(fp_line
			(start -0.12065 -0.2794)
			(end 0.12065 -0.2794)
			(stroke
				(width 0.1)
				(type default)
			)
			(layer "F.Fab")
		)
		(fp_line
			(start -0.12065 -0.305054)
			(end -0.12065 -0.2794)
			(stroke
				(width 0.1)
				(type default)
			)
			(layer "F.Fab")
		)
		(fp_line
			(start -0.67945 0.3048)
			(end -0.67945 -0.305054)
			(stroke
				(width 0.1)
				(type default)
			)
			(layer "F.Fab")
		)
		(fp_line
			(start -0.67945 -0.305054)
			(end -0.12065 -0.305054)
			(stroke
				(width 0.1)
				(type default)
			)
			(layer "F.Fab")
		)
		(pad "1" smd circle
			(at -0.40005 0 180)
			(size 0 0)
			(layers "F.Cu" "F.Mask" "F.Paste")
			(net "REV_ID<1>")
		)
		(pad "2" smd circle
			(at 0.40005 0 180)
			(size 0 0)
			(layers "F.Cu" "F.Mask" "F.Paste")
			(net "GND")
		)
	)
	(footprint ""
		(layer "F.Cu")
		(at 5.715 -28.448)
		(property "Reference" "U4"
			(at -0.635 -1.75133 0)
			(unlocked yes)
			(layer "F.SilkS")
			(effects
				(font
					(size 0.7874 0.5842)
					(thickness 0.1524)
				)
				(justify left)
			)
		)
		(property "Value" ""
			(at 0 0 0)
			(layer "F.Fab")
			(effects
				(font
					(size 1.27 1.27)
				)
			)
		)
		(duplicate_pad_numbers_are_jumpers no)
		(fp_line
			(start -1.335278 -1.100074)
			(end -1.335278 1.100074)
			(stroke
				(width 0.1524)
				(type default)
			)
			(layer "F.SilkS")
		)
		(fp_line
			(start -1.335278 1.100074)
			(end 1.335278 1.100074)
			(stroke
				(width 0.1524)
				(type default)
			)
			(layer "F.SilkS")
		)
		(fp_line
			(start 1.335278 -1.100074)
			(end -1.335278 -1.100074)
			(stroke
				(width 0.1524)
				(type default)
			)
			(layer "F.SilkS")
		)
		(fp_line
			(start 1.335278 1.100074)
			(end 1.335278 -1.100074)
			(stroke
				(width 0.1524)
				(type default)
			)
			(layer "F.SilkS")
		)
		(fp_line
			(start -0.674878 -1.100074)
			(end -0.674878 1.100074)
			(stroke
				(width 0.1)
				(type default)
			)
			(layer "F.Fab")
		)
		(fp_line
			(start -0.674878 1.100074)
			(end 0.674878 1.100074)
			(stroke
				(width 0.1)
				(type default)
			)
			(layer "F.Fab")
		)
		(fp_line
			(start 0.674878 -1.100074)
			(end -0.674878 -1.100074)
			(stroke
				(width 0.1)
				(type default)
			)
			(layer "F.Fab")
		)
		(fp_line
			(start 0.674878 1.100074)
			(end 0.674878 -1.100074)
			(stroke
				(width 0.1)
				(type default)
			)
			(layer "F.Fab")
		)
		(pad "D" smd rect
			(at 0.8001 0 270)
			(size 0.6096 0.8128)
			(layers "F.Cu" "F.Mask" "F.Paste")
			(net "PWR_LED_R1_N")
		)
		(pad "G" smd rect
			(at -0.8001 -0.649986 270)
			(size 0.6096 0.8128)
			(layers "F.Cu" "F.Mask" "F.Paste")
			(net "PWR_LED_R1")
		)
		(pad "S" smd rect
			(at -0.8001 0.649986 270)
			(size 0.6096 0.8128)
			(layers "F.Cu" "F.Mask" "F.Paste")
			(net "GND")
		)
	)
	(footprint ""
		(layer "F.Cu")
		(at 35.941 -32.385)
		(property "Reference" "C12"
			(at 0.762 -5.43433 0)
			(unlocked yes)
			(layer "F.SilkS")
			(effects
				(font
					(size 0.7874 0.5842)
					(thickness 0.1524)
				)
				(justify left)
			)
		)
		(property "Value" ""
			(at 0 0 0)
			(layer "F.Fab")
			(effects
				(font
					(size 1.27 1.27)
				)
			)
		)
		(duplicate_pad_numbers_are_jumpers no)
		(fp_line
			(start -1.524 -0.762)
			(end 1.524 -0.762)
			(stroke
				(width 0.1524)
				(type default)
			)
			(layer "F.SilkS")
		)
		(fp_line
			(start -1.524 0.762)
			(end -1.524 -0.762)
			(stroke
				(width 0.1524)
				(type default)
			)
			(layer "F.SilkS")
		)
		(fp_line
			(start 1.524 -0.762)
			(end 1.524 0.762)
			(stroke
				(width 0.1524)
				(type default)
			)
			(layer "F.SilkS")
		)
		(fp_line
			(start 1.524 0.762)
			(end -1.524 0.762)
			(stroke
				(width 0.1524)
				(type default)
			)
			(layer "F.SilkS")
		)
		(fp_line
			(start -1.1049 -0.724916)
			(end -1.1049 0.724916)
			(stroke
				(width 0.1)
				(type default)
			)
			(layer "F.Fab")
		)
		(fp_line
			(start -1.1049 0.724916)
			(end 1.1049 0.724916)
			(stroke
				(width 0.1)
				(type default)
			)
			(layer "F.Fab")
		)
		(fp_line
			(start 1.1049 -0.724916)
			(end -1.1049 -0.724916)
			(stroke
				(width 0.1)
				(type default)
			)
			(layer "F.Fab")
		)
		(fp_line
			(start 1.1049 0.724916)
			(end 1.1049 -0.724916)
			(stroke
				(width 0.1)
				(type default)
			)
			(layer "F.Fab")
		)
		(pad "1" smd rect
			(at -0.889 0 180)
			(size 1.016 1.27)
			(layers "F.Cu" "F.Mask" "F.Paste")
			(net "P5V_STBY_DEBUG")
		)
		(pad "2" smd rect
			(at 0.889 0 180)
			(size 1.016 1.27)
			(layers "F.Cu" "F.Mask" "F.Paste")
			(net "GND")
		)
	)
	(footprint ""
		(layer "F.Cu")
		(at 5.969 -60.325 180)
		(property "Reference" "C6"
			(at 3.175 -0.40767 0)
			(unlocked yes)
			(layer "F.SilkS")
			(effects
				(font
					(size 0.7874 0.5842)
					(thickness 0.1524)
				)
			)
		)
		(property "Value" ""
			(at 0 0 180)
			(layer "F.Fab")
			(effects
				(font
					(size 1.27 1.27)
				)
			)
		)
		(duplicate_pad_numbers_are_jumpers no)
		(fp_line
			(start 0.7874 0.4064)
			(end -0.7874 0.4064)
			(stroke
				(width 0.1524)
				(type default)
			)
			(layer "F.SilkS")
		)
		(fp_line
			(start 0.7874 -0.4064)
			(end 0.7874 0.4064)
			(stroke
				(width 0.1524)
				(type default)
			)
			(layer "F.SilkS")
		)
		(fp_line
			(start -0.7874 0.4064)
			(end -0.7874 -0.4064)
			(stroke
				(width 0.1524)
				(type default)
			)
			(layer "F.SilkS")
		)
		(fp_line
			(start -0.7874 -0.4064)
			(end 0.7874 -0.4064)
			(stroke
				(width 0.1524)
				(type default)
			)
			(layer "F.SilkS")
		)
		(fp_line
			(start 0.67945 0.3048)
			(end 0.120396 0.3048)
			(stroke
				(width 0.1)
				(type default)
			)
			(layer "F.Fab")
		)
		(fp_line
			(start 0.67945 -0.3048)
			(end 0.67945 0.3048)
			(stroke
				(width 0.1)
				(type default)
			)
			(layer "F.Fab")
		)
		(fp_line
			(start 0.12065 -0.2794)
			(end 0.12065 -0.3048)
			(stroke
				(width 0.1)
				(type default)
			)
			(layer "F.Fab")
		)
		(fp_line
			(start 0.12065 -0.3048)
			(end 0.67945 -0.3048)
			(stroke
				(width 0.1)
				(type default)
			)
			(layer "F.Fab")
		)
		(fp_line
			(start 0.120396 0.3048)
			(end 0.120396 0.2794)
			(stroke
				(width 0.1)
				(type default)
			)
			(layer "F.Fab")
		)
		(fp_line
			(start 0.120396 0.2794)
			(end -0.12065 0.2794)
			(stroke
				(width 0.1)
				(type default)
			)
			(layer "F.Fab")
		)
		(fp_line
			(start -0.12065 0.3048)
			(end -0.67945 0.3048)
			(stroke
				(width 0.1)
				(type default)
			)
			(layer "F.Fab")
		)
		(fp_line
			(start -0.12065 0.2794)
			(end -0.12065 0.3048)
			(stroke
				(width 0.1)
				(type default)
			)
			(layer "F.Fab")
		)
		(fp_line
			(start -0.12065 -0.2794)
			(end 0.12065 -0.2794)
			(stroke
				(width 0.1)
				(type default)
			)
			(layer "F.Fab")
		)
		(fp_line
			(start -0.12065 -0.305054)
			(end -0.12065 -0.2794)
			(stroke
				(width 0.1)
				(type default)
			)
			(layer "F.Fab")
		)
		(fp_line
			(start -0.67945 0.3048)
			(end -0.67945 -0.305054)
			(stroke
				(width 0.1)
				(type default)
			)
			(layer "F.Fab")
		)
		(fp_line
			(start -0.67945 -0.305054)
			(end -0.12065 -0.305054)
			(stroke
				(width 0.1)
				(type default)
			)
			(layer "F.Fab")
		)
		(pad "1" smd circle
			(at -0.40005 0 180)
			(size 0 0)
			(layers "F.Cu" "F.Mask" "F.Paste")
			(net "RST_SMB_R_N")
		)
		(pad "2" smd circle
			(at 0.40005 0 180)
			(size 0 0)
			(layers "F.Cu" "F.Mask" "F.Paste")
			(net "GND")
		)
	)
	(footprint ""
		(layer "F.Cu")
		(at 15.491206 -33.504124)
		(property "Reference" "H2"
			(at -4.061206 -0.886206 0)
			(unlocked yes)
			(layer "F.SilkS")
			(effects
				(font
					(size 0.7874 0.5842)
					(thickness 0.1524)
				)
				(justify left)
			)
		)
		(property "Value" ""
			(at 0 0 0)
			(layer "F.Fab")
			(effects
				(font
					(size 1.27 1.27)
				)
			)
		)
		(duplicate_pad_numbers_are_jumpers no)
		(fp_circle
			(center 0 0)
			(end 2.4003 0)
			(stroke
				(width 0.1524)
				(type default)
			)
			(fill no)
			(layer "F.SilkS")
		)
		(fp_arc
			(start 5.208524 4.039108)
			(mid -6.591207 -0.031941)
			(end 5.247132 -3.989324)
			(stroke
				(width 0.1524)
				(type default)
			)
			(layer "B.SilkS")
		)
		(fp_circle
			(center 0 0)
			(end 6.5913 0)
			(stroke
				(width 0.1)
				(type default)
			)
			(fill no)
			(layer "B.Fab")
		)
		(fp_circle
			(center 0 0)
			(end 2.4003 0)
			(stroke
				(width 0.1)
				(type default)
			)
			(fill no)
			(layer "F.Fab")
		)
		(pad "" np_thru_hole circle
			(at 0 0)
			(size 3.175 3.175)
			(drill 3.175)
			(layers "*.Cu" "*.Mask")
			(clearance 0.381)
			(thermal_gap 0.381)
		)
		(zone
			(layers "F.Cu" "B.Cu" "In1.Cu" "In2.Cu")
			(hatch none 0.5)
			(connect_pads
				(clearance 0)
			)
			(min_thickness 0.25)
			(keepout
				(tracks not_allowed)
				(vias allowed)
				(pads allowed)
				(copperpour not_allowed)
				(footprints allowed)
			)
			(placement
				(enabled no)
				(sheetname "")
			)
			(fill
				(thermal_gap 0.5)
				(thermal_bridge_width 0.5)
				(island_removal_mode 0)
			)
			(polygon
				(pts
					(arc
						(start 17.586706 -33.504124)
						(mid 13.395706 -33.504124)
						(end 17.586706 -33.504124)
					)
				)
			)
		)
	)
	(footprint ""
		(layer "F.Cu")
		(at 19.49577 -10.967974 -90)
		(property "Reference" "R3"
			(at 2.839974 -1.2319 90)
			(unlocked yes)
			(layer "F.SilkS")
			(effects
				(font
					(size 0.7874 0.5842)
					(thickness 0.1524)
				)
				(justify left)
			)
		)
		(property "Value" ""
			(at 0 0 270)
			(layer "F.Fab")
			(effects
				(font
					(size 1.27 1.27)
				)
			)
		)
		(duplicate_pad_numbers_are_jumpers no)
		(fp_line
			(start -1.651 0.8382)
			(end -1.651 -0.8382)
			(stroke
				(width 0.1524)
				(type default)
			)
			(layer "F.SilkS")
		)
		(fp_line
			(start 1.651 0.8382)
			(end -1.651 0.8382)
			(stroke
				(width 0.1524)
				(type default)
			)
			(layer "F.SilkS")
		)
		(fp_line
			(start -1.651 -0.8382)
			(end 1.651 -0.8382)
			(stroke
				(width 0.1524)
				(type default)
			)
			(layer "F.SilkS")
		)
		(fp_line
			(start 1.651 -0.8382)
			(end 1.651 0.8382)
			(stroke
				(width 0.1524)
				(type default)
			)
			(layer "F.SilkS")
		)
		(fp_line
			(start -1.559814 0.7366)
			(end -1.524 0.7366)
			(stroke
				(width 0.1)
				(type default)
			)
			(layer "F.Fab")
		)
		(fp_line
			(start -1.524 0.7366)
			(end 1.524 0.7366)
			(stroke
				(width 0.1)
				(type default)
			)
			(layer "F.Fab")
		)
		(fp_line
			(start 1.524 0.7366)
			(end 1.560576 0.7366)
			(stroke
				(width 0.1)
				(type default)
			)
			(layer "F.Fab")
		)
		(fp_line
			(start 1.560576 0.7366)
			(end 1.560576 -0.7366)
			(stroke
				(width 0.1)
				(type default)
			)
			(layer "F.Fab")
		)
		(fp_line
			(start -1.559814 -0.7366)
			(end -1.559814 0.7366)
			(stroke
				(width 0.1)
				(type default)
			)
			(layer "F.Fab")
		)
		(fp_line
			(start -1.524 -0.7366)
			(end -1.559814 -0.7366)
			(stroke
				(width 0.1)
				(type default)
			)
			(layer "F.Fab")
		)
		(fp_line
			(start 1.524 -0.7366)
			(end -1.524 -0.7366)
			(stroke
				(width 0.1)
				(type default)
			)
			(layer "F.Fab")
		)
		(fp_line
			(start 1.560576 -0.7366)
			(end 1.524 -0.7366)
			(stroke
				(width 0.1)
				(type default)
			)
			(layer "F.Fab")
		)
		(pad "1" smd rect
			(at -0.94996 0 90)
			(size 1.1176 1.3716)
			(layers "F.Cu" "F.Mask" "F.Paste")
			(net "P5V_STBY")
		)
		(pad "2" smd rect
			(at 0.94996 0 90)
			(size 1.1176 1.3716)
			(layers "F.Cu" "F.Mask" "F.Paste")
			(net "FM_PFR_LED_BLUE_R")
		)
	)
)
